# SCM (Grand Teton) — schematic netlist excerpt (pin names and nets, part order shuffled) for the footprints in the layout excerpt that follows; sources: Cadence DE-HDL packaged netlist, KiCad conversion of 12092022_DA0F0TMDCD0_F0T_Management_Board_D_brd_V3_OCP.brd

R844  Q_RES  4.7K 1% CHIP  pkg 0402LF  page 27 : A = P3V3_AUX ; B = SMB_BMC_ALERT12_N
C295  Q_CAP  0.1UF 25V 10% X7R  pkg 0402  page 15 : A = P5V_SENSOR ; B = GND

(kicad_pcb
	(version 20260206)
	(generator "pcbnew")
	(generator_version "10.0")
	(general
		(thickness 1.6)
		(legacy_teardrops no)
	)
	(paper "A4")
	(title_block
		(title "12092022_DA0F0TMDCD0_F0T_Management_Board_D_brd_V3_OCP.brd")
		(comment 1 "Grand Teton / footprints 889-890 of 1440")
	)
	(layers
		(0 "F.Cu" signal "TOP")
		(4 "In1.Cu" signal "GND")
		(6 "In2.Cu" signal "IN1")
		(8 "In3.Cu" signal "GND1")
		(10 "In4.Cu" signal "IN2")
		(12 "In5.Cu" signal "VCC")
		(14 "In6.Cu" signal "VCC1")
		(16 "In7.Cu" signal "IN3")
		(18 "In8.Cu" signal "GND2")
		(20 "In9.Cu" signal "IN4")
		(22 "In10.Cu" signal "GND3")
		(2 "B.Cu" signal "BOTTOM")
		(9 "F.Adhes" user "F.Adhesive")
		(11 "B.Adhes" user "B.Adhesive")
		(13 "F.Paste" user "Package Geometry/Pastemask Top")
		(15 "B.Paste" user "Package Geometry/Pastemask Bottom")
		(5 "F.SilkS" user "Ref Des/Silkscreen Top")
		(7 "B.SilkS" user "Ref Des/Silkscreen Bottom")
		(1 "F.Mask" user "Board Geometry/Soldermask Top")
		(3 "B.Mask" user "Board Geometry/Soldermask Bottom")
		(17 "Dwgs.User" user "User.Drawings")
		(19 "Cmts.User" user "User.Comments")
		(21 "Eco1.User" user "User.Eco1")
		(23 "Eco2.User" user "User.Eco2")
		(25 "Edge.Cuts" user "Board Geometry/Outline")
		(27 "Margin" user)
		(31 "F.CrtYd" user "Package Geometry/Place Bound Top")
		(29 "B.CrtYd" user "Package Geometry/Place Bound Bottom")
		(35 "F.Fab" user "Ref Des/Assembly Top")
		(33 "B.Fab" user "Ref Des/Assembly Bottom")
	)
	(footprint ""
		(layer "B.Cu")
		(at 50.91684 -63.94704 90)
		(property "Reference" "R844"
			(at 0 0 90)
			(layer "B.SilkS")
			(hide yes)
			(effects
				(font
					(size 1.27 1.27)
				)
				(justify mirror)
			)
		)
		(property "Value" ""
			(at 0 0 90)
			(layer "B.Fab")
			(effects
				(font
					(size 1.27 1.27)
				)
				(justify mirror)
			)
		)
		(duplicate_pad_numbers_are_jumpers no)
		(fp_line
			(start 0.7874 -0.4064)
			(end -0.7874 -0.4064)
			(stroke
				(width 0.1524)
				(type default)
			)
			(layer "B.SilkS")
		)
		(fp_line
			(start -0.7874 -0.4064)
			(end -0.7874 0.4064)
			(stroke
				(width 0.1524)
				(type default)
			)
			(layer "B.SilkS")
		)
		(fp_line
			(start 0.7874 0.4064)
			(end 0.7874 -0.4064)
			(stroke
				(width 0.1524)
				(type default)
			)
			(layer "B.SilkS")
		)
		(fp_line
			(start -0.7874 0.4064)
			(end 0.7874 0.4064)
			(stroke
				(width 0.1524)
				(type default)
			)
			(layer "B.SilkS")
		)
		(fp_line
			(start 0.67945 -0.305054)
			(end 0.12065 -0.305054)
			(stroke
				(width 0.1)
				(type default)
			)
			(layer "B.Fab")
		)
		(fp_line
			(start 0.12065 -0.305054)
			(end 0.12065 -0.2794)
			(stroke
				(width 0.1)
				(type default)
			)
			(layer "B.Fab")
		)
		(fp_line
			(start -0.12065 -0.3048)
			(end -0.67945 -0.3048)
			(stroke
				(width 0.1)
				(type default)
			)
			(layer "B.Fab")
		)
		(fp_line
			(start -0.67945 -0.3048)
			(end -0.67945 0.3048)
			(stroke
				(width 0.1)
				(type default)
			)
			(layer "B.Fab")
		)
		(fp_line
			(start 0.12065 -0.2794)
			(end -0.12065 -0.2794)
			(stroke
				(width 0.1)
				(type default)
			)
			(layer "B.Fab")
		)
		(fp_line
			(start -0.12065 -0.2794)
			(end -0.12065 -0.3048)
			(stroke
				(width 0.1)
				(type default)
			)
			(layer "B.Fab")
		)
		(fp_line
			(start 0.12065 0.2794)
			(end 0.12065 0.3048)
			(stroke
				(width 0.1)
				(type default)
			)
			(layer "B.Fab")
		)
		(fp_line
			(start -0.120396 0.2794)
			(end 0.12065 0.2794)
			(stroke
				(width 0.1)
				(type default)
			)
			(layer "B.Fab")
		)
		(fp_line
			(start 0.67945 0.3048)
			(end 0.67945 -0.305054)
			(stroke
				(width 0.1)
				(type default)
			)
			(layer "B.Fab")
		)
		(fp_line
			(start 0.12065 0.3048)
			(end 0.67945 0.3048)
			(stroke
				(width 0.1)
				(type default)
			)
			(layer "B.Fab")
		)
		(fp_line
			(start -0.120396 0.3048)
			(end -0.120396 0.2794)
			(stroke
				(width 0.1)
				(type default)
			)
			(layer "B.Fab")
		)
		(fp_line
			(start -0.67945 0.3048)
			(end -0.120396 0.3048)
			(stroke
				(width 0.1)
				(type default)
			)
			(layer "B.Fab")
		)
		(pad "1" smd circle
			(at 0.40005 0 270)
			(size 0 0)
			(layers "B.Cu" "B.Mask" "B.Paste")
			(net "P3V3_AUX")
		)
		(pad "2" smd circle
			(at -0.40005 0 270)
			(size 0 0)
			(layers "B.Cu" "B.Mask" "B.Paste")
			(net "SMB_BMC_ALERT12_N")
		)
	)
	(footprint ""
		(layer "B.Cu")
		(at 57.906666 -73.645014)
		(property "Reference" "C295"
			(at 0 0 0)
			(layer "B.SilkS")
			(hide yes)
			(effects
				(font
					(size 1.27 1.27)
				)
				(justify mirror)
			)
		)
		(property "Value" ""
			(at 0 0 0)
			(layer "B.Fab")
			(effects
				(font
					(size 1.27 1.27)
				)
				(justify mirror)
			)
		)
		(duplicate_pad_numbers_are_jumpers no)
		(fp_line
			(start -0.7874 -0.4064)
			(end -0.7874 0.4064)
			(stroke
				(width 0.1524)
				(type default)
			)
			(layer "B.SilkS")
		)
		(fp_line
			(start -0.7874 0.4064)
			(end 0.7874 0.4064)
			(stroke
				(width 0.1524)
				(type default)
			)
			(layer "B.SilkS")
		)
		(fp_line
			(start 0.7874 -0.4064)
			(end -0.7874 -0.4064)
			(stroke
				(width 0.1524)
				(type default)
			)
			(layer "B.SilkS")
		)
		(fp_line
			(start 0.7874 0.4064)
			(end 0.7874 -0.4064)
			(stroke
				(width 0.1524)
				(type default)
			)
			(layer "B.SilkS")
		)
		(fp_line
			(start -0.67945 -0.3048)
			(end -0.67945 0.3048)
			(stroke
				(width 0.1)
				(type default)
			)
			(layer "B.Fab")
		)
		(fp_line
			(start -0.67945 0.3048)
			(end -0.120396 0.3048)
			(stroke
				(width 0.1)
				(type default)
			)
			(layer "B.Fab")
		)
		(fp_line
			(start -0.12065 -0.3048)
			(end -0.67945 -0.3048)
			(stroke
				(width 0.1)
				(type default)
			)
			(layer "B.Fab")
		)
		(fp_line
			(start -0.12065 -0.2794)
			(end -0.12065 -0.3048)
			(stroke
				(width 0.1)
				(type default)
			)
			(layer "B.Fab")
		)
		(fp_line
			(start -0.120396 0.2794)
			(end 0.12065 0.2794)
			(stroke
				(width 0.1)
				(type default)
			)
			(layer "B.Fab")
		)
		(fp_line
			(start -0.120396 0.3048)
			(end -0.120396 0.2794)
			(stroke
				(width 0.1)
				(type default)
			)
			(layer "B.Fab")
		)
		(fp_line
			(start 0.12065 -0.305054)
			(end 0.12065 -0.2794)
			(stroke
				(width 0.1)
				(type default)
			)
			(layer "B.Fab")
		)
		(fp_line
			(start 0.12065 -0.2794)
			(end -0.12065 -0.2794)
			(stroke
				(width 0.1)
				(type default)
			)
			(layer "B.Fab")
		)
		(fp_line
			(start 0.12065 0.2794)
			(end 0.12065 0.3048)
			(stroke
				(width 0.1)
				(type default)
			)
			(layer "B.Fab")
		)
		(fp_line
			(start 0.12065 0.3048)
			(end 0.67945 0.3048)
			(stroke
				(width 0.1)
				(type default)
			)
			(layer "B.Fab")
		)
		(fp_line
			(start 0.67945 -0.305054)
			(end 0.12065 -0.305054)
			(stroke
				(width 0.1)
				(type default)
			)
			(layer "B.Fab")
		)
		(fp_line
			(start 0.67945 0.3048)
			(end 0.67945 -0.305054)
			(stroke
				(width 0.1)
				(type default)
			)
			(layer "B.Fab")
		)
		(pad "1" smd circle
			(at 0.40005 0 180)
			(size 0 0)
			(layers "B.Cu" "B.Mask" "B.Paste")
			(net "P5V_SENSOR")
		)
		(pad "2" smd circle
			(at -0.40005 0 180)
			(size 0 0)
			(layers "B.Cu" "B.Mask" "B.Paste")
			(net "GND")
		)
	)
)
